FILE_TYPE = CONNECTIVITY;
{Allegro Design Entry HDL 17.4-2019 S026 (4007227) 1/17/2022}
"PAGE_NUMBER" = 389;
0"NC";
END.
